# T6G (Grand Teton) — schematic netlist excerpt (pin names and nets, part order shuffled) for the footprints in the layout excerpt that follows; sources: Cadence DE-HDL packaged netlist, KiCad conversion of 04192023_DAF0TMB3IC0_F0TG_MB_C_brd_V02_OCP.brd

PR2525  Q_RES  10 1% CHIP  pkg 0402LF  page 266 : A = P12V_HSC_SENSE2_N ; B = P12V_HSC_SENSE2_R2_N
R75  Q_RES  0 5% CHIP  pkg 0402LF  page 132 : A = NCSI_BMC_TXD0_R ; B = RMII_BMC_OCP_TXD_0

(kicad_pcb
	(version 20260206)
	(generator "pcbnew")
	(generator_version "10.0")
	(general
		(thickness 1.6)
		(legacy_teardrops no)
	)
	(paper "A4")
	(title_block
		(title "04192023_DAF0TMB3IC0_F0TG_MB_C_brd_V02_OCP.brd")
		(comment 1 "Grand Teton / footprints 5562-5563 of 8354")
	)
	(layers
		(0 "F.Cu" signal "TOP")
		(4 "In1.Cu" signal "GND")
		(6 "In2.Cu" signal "IN1")
		(8 "In3.Cu" signal "GND1")
		(10 "In4.Cu" signal "IN2")
		(12 "In5.Cu" signal "GND2")
		(14 "In6.Cu" signal "IN3")
		(16 "In7.Cu" signal "GND3")
		(18 "In8.Cu" signal "VCC")
		(20 "In9.Cu" signal "VCC1")
		(22 "In10.Cu" signal "GND4")
		(24 "In11.Cu" signal "IN4")
		(26 "In12.Cu" signal "GND5")
		(28 "In13.Cu" signal "IN5")
		(30 "In14.Cu" signal "GND6")
		(32 "In15.Cu" signal "IN6")
		(34 "In16.Cu" signal "GND7")
		(2 "B.Cu" signal "BOTTOM")
		(9 "F.Adhes" user "F.Adhesive")
		(11 "B.Adhes" user "B.Adhesive")
		(13 "F.Paste" user "Package Geometry/Pastemask Top")
		(15 "B.Paste" user "Package Geometry/Pastemask Bottom")
		(5 "F.SilkS" user "Ref Des/Silkscreen Top")
		(7 "B.SilkS" user "Ref Des/Silkscreen Bottom")
		(1 "F.Mask" user "Board Geometry/Soldermask Top")
		(3 "B.Mask" user "Board Geometry/Soldermask Bottom")
		(17 "Dwgs.User" user "User.Drawings")
		(19 "Cmts.User" user "User.Comments")
		(21 "Eco1.User" user "User.Eco1")
		(23 "Eco2.User" user "User.Eco2")
		(25 "Edge.Cuts" user "Board Geometry/Outline")
		(27 "Margin" user)
		(31 "F.CrtYd" user "Package Geometry/Place Bound Top")
		(29 "B.CrtYd" user "Package Geometry/Place Bound Bottom")
		(35 "F.Fab" user "Ref Des/Assembly Top")
		(33 "B.Fab" user "Ref Des/Assembly Bottom")
	)
	(footprint ""
		(layer "B.Cu")
		(at 206.429356 -386.152136 180)
		(property "Reference" "PR2525"
			(at 0 0 0)
			(layer "B.SilkS")
			(hide yes)
			(effects
				(font
					(size 1.27 1.27)
				)
				(justify mirror)
			)
		)
		(property "Value" ""
			(at 0 0 0)
			(layer "B.Fab")
			(effects
				(font
					(size 1.27 1.27)
				)
				(justify mirror)
			)
		)
		(duplicate_pad_numbers_are_jumpers no)
		(fp_line
			(start 0.7874 0.4064)
			(end 0.7874 -0.4064)
			(stroke
				(width 0.1524)
				(type default)
			)
			(layer "B.SilkS")
		)
		(fp_line
			(start 0.7874 -0.4064)
			(end -0.7874 -0.4064)
			(stroke
				(width 0.1524)
				(type default)
			)
			(layer "B.SilkS")
		)
		(fp_line
			(start -0.7874 0.4064)
			(end 0.7874 0.4064)
			(stroke
				(width 0.1524)
				(type default)
			)
			(layer "B.SilkS")
		)
		(fp_line
			(start -0.7874 -0.4064)
			(end -0.7874 0.4064)
			(stroke
				(width 0.1524)
				(type default)
			)
			(layer "B.SilkS")
		)
		(fp_line
			(start 0.67945 0.3048)
			(end 0.67945 -0.305054)
			(stroke
				(width 0.1)
				(type default)
			)
			(layer "B.Fab")
		)
		(fp_line
			(start 0.67945 -0.305054)
			(end 0.12065 -0.305054)
			(stroke
				(width 0.1)
				(type default)
			)
			(layer "B.Fab")
		)
		(fp_line
			(start 0.12065 0.3048)
			(end 0.67945 0.3048)
			(stroke
				(width 0.1)
				(type default)
			)
			(layer "B.Fab")
		)
		(fp_line
			(start 0.12065 0.2794)
			(end 0.12065 0.3048)
			(stroke
				(width 0.1)
				(type default)
			)
			(layer "B.Fab")
		)
		(fp_line
			(start 0.12065 -0.2794)
			(end -0.12065 -0.2794)
			(stroke
				(width 0.1)
				(type default)
			)
			(layer "B.Fab")
		)
		(fp_line
			(start 0.12065 -0.305054)
			(end 0.12065 -0.2794)
			(stroke
				(width 0.1)
				(type default)
			)
			(layer "B.Fab")
		)
		(fp_line
			(start -0.120396 0.3048)
			(end -0.120396 0.2794)
			(stroke
				(width 0.1)
				(type default)
			)
			(layer "B.Fab")
		)
		(fp_line
			(start -0.120396 0.2794)
			(end 0.12065 0.2794)
			(stroke
				(width 0.1)
				(type default)
			)
			(layer "B.Fab")
		)
		(fp_line
			(start -0.12065 -0.2794)
			(end -0.12065 -0.3048)
			(stroke
				(width 0.1)
				(type default)
			)
			(layer "B.Fab")
		)
		(fp_line
			(start -0.12065 -0.3048)
			(end -0.67945 -0.3048)
			(stroke
				(width 0.1)
				(type default)
			)
			(layer "B.Fab")
		)
		(fp_line
			(start -0.67945 0.3048)
			(end -0.120396 0.3048)
			(stroke
				(width 0.1)
				(type default)
			)
			(layer "B.Fab")
		)
		(fp_line
			(start -0.67945 -0.3048)
			(end -0.67945 0.3048)
			(stroke
				(width 0.1)
				(type default)
			)
			(layer "B.Fab")
		)
		(pad "1" smd circle
			(at 0.40005 0)
			(size 0 0)
			(layers "B.Cu" "B.Mask" "B.Paste")
			(net "P12V_HSC_SENSE2_N")
		)
		(pad "2" smd circle
			(at -0.40005 0)
			(size 0 0)
			(layers "B.Cu" "B.Mask" "B.Paste")
			(net "P12V_HSC_SENSE2_R2_N")
		)
	)
	(footprint ""
		(layer "B.Cu")
		(at 217.551762 -69.483478 180)
		(property "Reference" "R75"
			(at 0 0 0)
			(layer "B.SilkS")
			(hide yes)
			(effects
				(font
					(size 1.27 1.27)
				)
				(justify mirror)
			)
		)
		(property "Value" ""
			(at 0 0 0)
			(layer "B.Fab")
			(effects
				(font
					(size 1.27 1.27)
				)
				(justify mirror)
			)
		)
		(duplicate_pad_numbers_are_jumpers no)
		(fp_line
			(start 0.7874 0.4064)
			(end 0.7874 -0.4064)
			(stroke
				(width 0.1524)
				(type default)
			)
			(layer "B.SilkS")
		)
		(fp_line
			(start 0.7874 -0.4064)
			(end -0.7874 -0.4064)
			(stroke
				(width 0.1524)
				(type default)
			)
			(layer "B.SilkS")
		)
		(fp_line
			(start -0.7874 0.4064)
			(end 0.7874 0.4064)
			(stroke
				(width 0.1524)
				(type default)
			)
			(layer "B.SilkS")
		)
		(fp_line
			(start -0.7874 -0.4064)
			(end -0.7874 0.4064)
			(stroke
				(width 0.1524)
				(type default)
			)
			(layer "B.SilkS")
		)
		(fp_line
			(start 0.67945 0.3048)
			(end 0.67945 -0.305054)
			(stroke
				(width 0.1)
				(type default)
			)
			(layer "B.Fab")
		)
		(fp_line
			(start 0.67945 -0.305054)
			(end 0.12065 -0.305054)
			(stroke
				(width 0.1)
				(type default)
			)
			(layer "B.Fab")
		)
		(fp_line
			(start 0.12065 0.3048)
			(end 0.67945 0.3048)
			(stroke
				(width 0.1)
				(type default)
			)
			(layer "B.Fab")
		)
		(fp_line
			(start 0.12065 0.2794)
			(end 0.12065 0.3048)
			(stroke
				(width 0.1)
				(type default)
			)
			(layer "B.Fab")
		)
		(fp_line
			(start 0.12065 -0.2794)
			(end -0.12065 -0.2794)
			(stroke
				(width 0.1)
				(type default)
			)
			(layer "B.Fab")
		)
		(fp_line
			(start 0.12065 -0.305054)
			(end 0.12065 -0.2794)
			(stroke
				(width 0.1)
				(type default)
			)
			(layer "B.Fab")
		)
		(fp_line
			(start -0.120396 0.3048)
			(end -0.120396 0.2794)
			(stroke
				(width 0.1)
				(type default)
			)
			(layer "B.Fab")
		)
		(fp_line
			(start -0.120396 0.2794)
			(end 0.12065 0.2794)
			(stroke
				(width 0.1)
				(type default)
			)
			(layer "B.Fab")
		)
		(fp_line
			(start -0.12065 -0.2794)
			(end -0.12065 -0.3048)
			(stroke
				(width 0.1)
				(type default)
			)
			(layer "B.Fab")
		)
		(fp_line
			(start -0.12065 -0.3048)
			(end -0.67945 -0.3048)
			(stroke
				(width 0.1)
				(type default)
			)
			(layer "B.Fab")
		)
		(fp_line
			(start -0.67945 0.3048)
			(end -0.120396 0.3048)
			(stroke
				(width 0.1)
				(type default)
			)
			(layer "B.Fab")
		)
		(fp_line
			(start -0.67945 -0.3048)
			(end -0.67945 0.3048)
			(stroke
				(width 0.1)
				(type default)
			)
			(layer "B.Fab")
		)
		(pad "1" smd circle
			(at 0.40005 0)
			(size 0 0)
			(layers "B.Cu" "B.Mask" "B.Paste")
			(net "NCSI_BMC_TXD0_R")
		)
		(pad "2" smd circle
			(at -0.40005 0)
			(size 0 0)
			(layers "B.Cu" "B.Mask" "B.Paste")
			(net "RMII_BMC_OCP_TXD_0")
		)
	)
)
